G04 ================== begin FILE IDENTIFICATION RECORD ==================*
G04 Layout Name:  12523-1.brd*
G04 Film Name:    L3VCC*
G04 File Format:  Gerber RS274X*
G04 File Origin:  Cadence Allegro 16.2-s031*
G04 Origin Date:  Fri Oct 19 14:59:13 2012*
G04 *
G04 Layer:  VIA CLASS/L3VCC*
G04 Layer:  PIN/L3VCC*
G04 Layer:  PACKAGE GEOMETRY/PWRVCC*
G04 Layer:  ETCH/L3VCC*
G04 Layer:  DRAWING FORMAT/LAYER_PCB_STORY*
G04 Layer:  DRAWING FORMAT/LAYER_L3VCC*
G04 *
G04 Offset:    (0.00 0.00)*
G04 Mirror:    No*
G04 Mode:      Negative*
G04 Rotation:  0*
G04 FullContactRelief:  No*
G04 UndefLineWidth:     6.00*
G04 ================== end FILE IDENTIFICATION RECORD ====================*
%FSLAX35Y35*MOIN*%
%IR0*IPPOS*OFA0.00000B0.00000*MIA0B0*SFA1.00000B1.00000*%
%AMMACRO17*
4,1,14,.0267,.01255,
.028474,.007723,
.029382,.002661,
.029398,-.002481,
.02852,-.007549,
.026776,-.012386,
.0267,-.01255,
.03042,-.01628,
.032785,-.01075,
.034154,-.004894,
.034484,.001111,
.033768,.007082,
.032025,.012838,
.03042,.01628,
.0267,.01255,
90.*
4,1,14,.01255,-.0267,
.007723,-.028474,
.002661,-.029382,
-.002481,-.029398,
-.007549,-.02852,
-.012386,-.026776,
-.01255,-.0267,
-.01628,-.03042,
-.01075,-.032785,
-.004894,-.034154,
.001111,-.034484,
.007082,-.033768,
.012838,-.032025,
.01628,-.03042,
.01255,-.0267,
90.*
4,1,14,-.0267,-.01255,
-.028474,-.007723,
-.029382,-.002661,
-.029398,.002481,
-.02852,.007549,
-.026776,.012386,
-.0267,.01255,
-.03042,.01628,
-.032785,.01075,
-.034154,.004894,
-.034484,-.001111,
-.033768,-.007082,
-.032025,-.012838,
-.03042,-.01628,
-.0267,-.01255,
90.*
4,1,14,-.01255,.0267,
-.007723,.028474,
-.002661,.029382,
.002481,.029398,
.007549,.02852,
.012386,.026776,
.01255,.0267,
.01628,.03042,
.01075,.032785,
.004894,.034154,
-.001111,.034484,
-.007082,.033768,
-.012838,.032025,
-.01628,.03042,
-.01255,.0267,
90.*
%
%ADD17MACRO17*%
%AMMACRO16*
4,1,16,.07909,.0508,
.08671,.036294,
.091695,.020686,
.093894,.004449,
.09324,-.011923,
.089753,-.027933,
.083539,-.043094,
.07909,-.0508,
.0827,-.05442,
.090894,-.039233,
.096325,-.022853,
.09883,-.005779,
.098332,.01147,
.094847,.028371,
.088479,.04441,
.0827,.05442,
.07909,.0508,
0.0*
4,1,16,.0508,-.07909,
.036294,-.08671,
.020686,-.091695,
.004449,-.093894,
-.011923,-.09324,
-.027933,-.089753,
-.043094,-.083539,
-.0508,-.07909,
-.05442,-.0827,
-.039233,-.090894,
-.022853,-.096325,
-.005779,-.09883,
.01147,-.098332,
.028371,-.094847,
.04441,-.088479,
.05442,-.0827,
.0508,-.07909,
0.0*
4,1,16,-.07909,-.0508,
-.08671,-.036294,
-.091695,-.020686,
-.093894,-.004449,
-.09324,.011923,
-.089753,.027933,
-.083539,.043094,
-.07909,.0508,
-.0827,.05442,
-.090894,.039233,
-.096325,.022853,
-.09883,.005779,
-.098332,-.01147,
-.094847,-.028371,
-.088479,-.04441,
-.0827,-.05442,
-.07909,-.0508,
0.0*
4,1,16,-.0508,.07909,
-.036294,.08671,
-.020686,.091695,
-.004449,.093894,
.011923,.09324,
.027933,.089753,
.043094,.083539,
.0508,.07909,
.05442,.0827,
.039233,.090894,
.022853,.096325,
.005779,.09883,
-.01147,.098332,
-.028371,.094847,
-.04441,.088479,
-.05442,.0827,
-.0508,.07909,
0.0*
%
%ADD16MACRO16*%
%ADD19C,.062*%
%ADD13C,.036*%
%ADD20C,.065*%
%ADD18C,.069*%
%AMMACRO15*
4,1,15,.00398,.00044,
.003999,.000208,
.004004,-.000025,
.003996,-.000258,
.00398,-.00044,
.00483,-.00129,
.004897,-.001007,
.004947,-.000721,
.004981,-.000432,
.004997,-.000141,
.004997,.000149,
.00498,.00044,
.004946,.000729,
.004895,.001015,
.00483,.00129,
.00398,.00044,
90.*
4,1,15,.00044,-.00398,
.000208,-.003999,
-.000025,-.004004,
-.000258,-.003996,
-.00044,-.00398,
-.00129,-.00483,
-.001007,-.004897,
-.000721,-.004947,
-.000432,-.004981,
-.000141,-.004997,
.000149,-.004997,
.00044,-.00498,
.000729,-.004946,
.001015,-.004895,
.00129,-.00483,
.00044,-.00398,
90.*
4,1,15,-.00398,-.00044,
-.003999,-.000208,
-.004004,.000025,
-.003996,.000258,
-.00398,.00044,
-.00483,.00129,
-.004897,.001007,
-.004947,.000721,
-.004981,.000432,
-.004997,.000141,
-.004997,-.000149,
-.00498,-.00044,
-.004946,-.000729,
-.004895,-.001015,
-.00483,-.00129,
-.00398,-.00044,
90.*
4,1,15,-.00044,.00398,
-.000208,.003999,
.000025,.004004,
.000258,.003996,
.00044,.00398,
.00129,.00483,
.001007,.004897,
.000721,.004947,
.000432,.004981,
.000141,.004997,
-.000149,.004997,
-.00044,.00498,
-.000729,.004946,
-.001015,.004895,
-.00129,.00483,
-.00044,.00398,
90.*
%
%ADD15MACRO15*%
%AMMACRO14*
4,1,15,.00398,.00044,
.003999,.000208,
.004004,-.000025,
.003996,-.000258,
.00398,-.00044,
.00483,-.00129,
.004897,-.001007,
.004947,-.000721,
.004981,-.000432,
.004997,-.000141,
.004997,.000149,
.00498,.00044,
.004946,.000729,
.004895,.001015,
.00483,.00129,
.00398,.00044,
0.0*
4,1,15,.00044,-.00398,
.000208,-.003999,
-.000025,-.004004,
-.000258,-.003996,
-.00044,-.00398,
-.00129,-.00483,
-.001007,-.004897,
-.000721,-.004947,
-.000432,-.004981,
-.000141,-.004997,
.000149,-.004997,
.00044,-.00498,
.000729,-.004946,
.001015,-.004895,
.00129,-.00483,
.00044,-.00398,
0.0*
4,1,15,-.00398,-.00044,
-.003999,-.000208,
-.004004,.000025,
-.003996,.000258,
-.00398,.00044,
-.00483,.00129,
-.004897,.001007,
-.004947,.000721,
-.004981,.000432,
-.004997,.000141,
-.004997,-.000149,
-.00498,-.00044,
-.004946,-.000729,
-.004895,-.001015,
-.00483,-.00129,
-.00398,-.00044,
0.0*
4,1,15,-.00044,.00398,
-.000208,.003999,
.000025,.004004,
.000258,.003996,
.00044,.00398,
.00129,.00483,
.001007,.004897,
.000721,.004947,
.000432,.004981,
.000141,.004997,
-.000149,.004997,
-.00044,.00498,
-.000729,.004946,
-.001015,.004895,
-.00129,.00483,
-.00044,.00398,
0.0*
%
%ADD14MACRO14*%
%ADD10C,.114*%
%ADD21C,.186*%
%AMMACRO12*
4,1,15,.00398,.00044,
.003999,.000208,
.004004,-.000025,
.003996,-.000258,
.00398,-.00044,
.00483,-.00129,
.004897,-.001007,
.004947,-.000721,
.004981,-.000432,
.004997,-.000141,
.004997,.000149,
.00498,.00044,
.004946,.000729,
.004895,.001015,
.00483,.00129,
.00398,.00044,
180.*
4,1,15,.00044,-.00398,
.000208,-.003999,
-.000025,-.004004,
-.000258,-.003996,
-.00044,-.00398,
-.00129,-.00483,
-.001007,-.004897,
-.000721,-.004947,
-.000432,-.004981,
-.000141,-.004997,
.000149,-.004997,
.00044,-.00498,
.000729,-.004946,
.001015,-.004895,
.00129,-.00483,
.00044,-.00398,
180.*
4,1,15,-.00398,-.00044,
-.003999,-.000208,
-.004004,.000025,
-.003996,.000258,
-.00398,.00044,
-.00483,.00129,
-.004897,.001007,
-.004947,.000721,
-.004981,.000432,
-.004997,.000141,
-.004997,-.000149,
-.00498,-.00044,
-.004946,-.000729,
-.004895,-.001015,
-.00483,-.00129,
-.00398,-.00044,
180.*
4,1,15,-.00044,.00398,
-.000208,.003999,
.000025,.004004,
.000258,.003996,
.00044,.00398,
.00129,.00483,
.001007,.004897,
.000721,.004947,
.000432,.004981,
.000141,.004997,
-.000149,.004997,
-.00044,.00498,
-.000729,.004946,
-.001015,.004895,
-.00129,.00483,
-.00044,.00398,
180.*
%
%ADD12MACRO12*%
%AMMACRO11*
4,1,16,.07256,.04427,
.079145,.030998,
.083325,.016783,
.084974,.002059,
.08404,-.012728,
.080553,-.027128,
.074619,-.040704,
.07256,-.04427,
.07619,-.04791,
.083352,-.033952,
.087981,-.018962,
.089937,-.003396,
.089161,.012273,
.085675,.027569,
.079586,.042027,
.07619,.04791,
.07256,.04427,
0.0*
4,1,16,.04427,-.07256,
.030998,-.079145,
.016783,-.083325,
.002059,-.084974,
-.012728,-.08404,
-.027128,-.080553,
-.040704,-.074619,
-.04427,-.07256,
-.04791,-.07619,
-.033952,-.083352,
-.018962,-.087981,
-.003396,-.089937,
.012273,-.089161,
.027569,-.085675,
.042027,-.079586,
.04791,-.07619,
.04427,-.07256,
0.0*
4,1,16,-.07256,-.04427,
-.079145,-.030998,
-.083325,-.016783,
-.084974,-.002059,
-.08404,.012728,
-.080553,.027128,
-.074619,.040704,
-.07256,.04427,
-.07619,.04791,
-.083352,.033952,
-.087981,.018962,
-.089937,.003396,
-.089161,-.012273,
-.085675,-.027569,
-.079586,-.042027,
-.07619,-.04791,
-.07256,-.04427,
0.0*
4,1,16,-.04427,.07256,
-.030998,.079145,
-.016783,.083325,
-.002059,.084974,
.012728,.08404,
.027128,.080553,
.040704,.074619,
.04427,.07256,
.04791,.07619,
.033952,.083352,
.018962,.087981,
.003396,.089937,
-.012273,.089161,
-.027569,.085675,
-.042027,.079586,
-.04791,.07619,
-.04427,.07256,
0.0*
%
%ADD11MACRO11*%
%ADD22C,.02*%
%ADD23C,.006*%
%ADD25C,.05806*%
%ADD24C,.18206*%
G75*
%LPD*%
G75*
G36*
G01X-49307Y-6000D02*
X646394D01*
Y478441D01*
X-49307D01*
Y-6000D01*
G37*
%LPC*%
G75*
G36*
G01X627069Y348740D02*
X635394Y343190D01*
Y319787D01*
X624646D01*
G03X617705Y312846I0J-6941D01*
G01Y135972D01*
G03X624646Y129031I6941J0D01*
G01X635394D01*
Y5000D01*
X5000D01*
Y79500D01*
X38086D01*
X55086Y62500D01*
X56000D01*
X547854Y62440D01*
X591000Y105586D01*
Y142086D01*
X609500Y160586D01*
Y195414D01*
X605914Y199000D01*
X566086D01*
X554585Y187500D01*
X486893Y187440D01*
X417915Y187500D01*
X410914Y194440D01*
X-33307D01*
Y287047D01*
X-1378D01*
G03Y299803I0J6378D01*
G01X-33307D01*
Y360945D01*
X-3937D01*
G03X5000Y369882I0J8937D01*
G01Y467441D01*
X635394D01*
Y389094D01*
X627067Y383543D01*
X545906D01*
G03X536969Y374606I0J-8937D01*
G01Y357677D01*
G03X545906Y348740I8937J0D01*
G01X627069D01*
G37*
G36*
G01X-33307Y115906D02*
Y192500D01*
X410086D01*
X417085Y185500D01*
X486893Y185440D01*
X555415Y185500D01*
X566914Y197000D01*
X605086D01*
X607500Y194586D01*
Y161414D01*
X589000Y142914D01*
Y106414D01*
X547026Y64440D01*
X56000Y64500D01*
X55914D01*
X38914Y81500D01*
X5000D01*
Y106969D01*
G03X-3937Y115906I-8937J0D01*
G01X-33307D01*
G37*
%LPD*%
G75*
G36*
G01X25118Y219438D02*
X21181D01*
G02X14242Y226378I1J6940D01*
G01Y246063D01*
G02X21181Y253002I6939J0D01*
G01X25118D01*
G02X32058Y246063I1J-6939D01*
G01Y226378D01*
G02X25118Y219438I-6940J0D01*
G37*
G54D25*
X599055Y90551D03*
Y59055D03*
G54D24*
X600709Y311909D03*
Y136909D03*
G54D17*
X570709Y161889D03*
X580709D03*
X570709Y191889D03*
X580709D03*
X570709Y181889D03*
X580709D03*
X570709Y171889D03*
X580709D03*
X570709Y276929D03*
X580709D03*
X570709Y266929D03*
X580709D03*
X570709Y256929D03*
X580709D03*
X570709Y286929D03*
X580709D03*
X590709Y161889D03*
X600709D03*
Y214409D03*
X590709Y204409D03*
Y191889D03*
X600709D03*
X590709Y181889D03*
X600709D03*
X590709Y171889D03*
X600709D03*
X590709Y244409D03*
Y276929D03*
X600709D03*
X590709Y266929D03*
X600709D03*
X590709Y256929D03*
X600709D03*
Y234409D03*
X590709Y224409D03*
Y286929D03*
X600709D03*
G54D16*
X498661Y23622D03*
X589212Y448818D03*
G54D19*
X599055Y59055D03*
Y90551D03*
G54D13*
X3398Y326936D03*
X2334Y318654D03*
X1494Y343705D03*
X5694D03*
X10000Y332000D03*
X30923Y335665D03*
X26723D03*
X57398Y348682D03*
X52705Y348626D03*
X48325Y348514D03*
X37500Y386500D03*
X60052Y394674D03*
X55352D03*
X51094Y394478D03*
X520500Y331000D03*
X561500Y232000D03*
X557000Y231500D03*
X543900Y314000D03*
X600000Y337500D03*
Y342000D03*
X595500D03*
Y337500D03*
X612798Y413000D03*
X617798D03*
G54D20*
X596102Y66929D03*
X602008Y74803D03*
X596102Y82677D03*
G54D18*
X570709Y214409D03*
X580709D03*
X570709Y204409D03*
X580709D03*
X570709Y244409D03*
X580709D03*
X570709Y234409D03*
X580709D03*
X570709Y224409D03*
X580709D03*
X590709Y214409D03*
X600709Y204409D03*
Y244409D03*
X590709Y234409D03*
X600709Y224409D03*
G54D15*
X22000Y387500D03*
X55500Y417000D03*
X512500Y323000D03*
X492000Y321000D03*
X506500Y305500D03*
X520381Y300757D03*
X537136Y326402D03*
X525161Y311000D03*
G54D14*
X25500Y353000D03*
X25000Y343000D03*
X33986Y362933D03*
X22000Y374500D03*
X61898Y358936D03*
X546600Y257971D03*
G54D10*
X-23621Y15748D03*
Y937008D03*
X1312285Y15747D03*
G54D21*
X600709Y136909D03*
Y311909D03*
G54D12*
X6419Y116482D03*
X-3350Y117504D03*
X6419Y126482D03*
X-3581D03*
X6419Y136482D03*
X-3581D03*
X6419Y146482D03*
X-3581D03*
X6419Y156482D03*
X-3581D03*
X-2602Y206936D03*
X7398D03*
X-2602Y216936D03*
X7398D03*
X6419Y166482D03*
X-3581D03*
Y176482D03*
X6419D03*
X-2602Y226936D03*
X7398D03*
X-2602Y246936D03*
X7398D03*
X-2602Y236936D03*
X7398D03*
Y256936D03*
X-2602D03*
Y266936D03*
X7398D03*
Y276936D03*
X-2602D03*
X7398Y286936D03*
X-2948Y302202D03*
X-2602Y316436D03*
X-7102Y327202D03*
X-6940Y316247D03*
X-6602Y347202D03*
X-7102Y337202D03*
X-6602Y357202D03*
X6898Y387436D03*
X6398Y369936D03*
X6898Y445436D03*
Y465436D03*
X16419Y6482D03*
Y26482D03*
X36419Y6482D03*
Y26482D03*
X56419Y46482D03*
X16419Y86482D03*
X36419D03*
X56419Y66482D03*
Y86482D03*
X26419Y116482D03*
X16419D03*
X26419Y126482D03*
X16419D03*
X26419Y136482D03*
X16419D03*
X26419Y146482D03*
X16419D03*
X26419Y156482D03*
X16419D03*
X36419Y126482D03*
X16419Y106482D03*
X36419D03*
Y146482D03*
X56419Y126482D03*
Y106482D03*
Y146482D03*
X27398Y206936D03*
X17398D03*
X27398Y216936D03*
X17398D03*
X26419Y186482D03*
X16419D03*
X26419Y166482D03*
X16419D03*
Y176482D03*
X26419D03*
X36419Y186482D03*
Y166482D03*
X56419Y186482D03*
Y166482D03*
X57398Y206936D03*
X37398D03*
X17398Y256936D03*
X27398D03*
Y266936D03*
X17398D03*
X57398Y226936D03*
X36769D03*
X57398Y246936D03*
Y266936D03*
X36769Y246936D03*
X37398Y266936D03*
X17398Y276936D03*
X27398Y286936D03*
X17398D03*
X27398Y276936D03*
X57398Y286936D03*
X37398D03*
X64398Y304436D03*
X34898Y344936D03*
X62398Y338436D03*
X62000Y442500D03*
X35830Y442464D03*
X19898Y465436D03*
X39898D03*
X76419Y46482D03*
X116419D03*
X96419D03*
X76419Y66482D03*
Y86482D03*
X116419Y66482D03*
X96419D03*
X116419Y86482D03*
X96419D03*
X76419Y126482D03*
Y106482D03*
Y146482D03*
X116419Y126482D03*
Y106482D03*
X96419Y126482D03*
Y106482D03*
X116419Y146482D03*
X96419D03*
X76419Y186482D03*
Y166482D03*
X77398Y206936D03*
X116419Y186482D03*
Y166482D03*
X96419Y186482D03*
Y166482D03*
X117398Y206936D03*
X97398D03*
X77398Y226936D03*
Y246936D03*
Y266936D03*
X117398Y226936D03*
X97398D03*
X117398Y246936D03*
X97398D03*
Y266936D03*
X116398D03*
X77398Y286936D03*
X86398Y303936D03*
X97398Y286936D03*
X116398D03*
X77898Y338436D03*
X78398Y358436D03*
X115330Y337964D03*
X96398Y337936D03*
X115330Y377964D03*
Y357964D03*
X95330Y377964D03*
Y357964D03*
X105330Y442964D03*
X85330D03*
X75500Y417500D03*
X115330Y417964D03*
X95330D03*
X91500Y465500D03*
X117500D03*
X67830Y465464D03*
X136419Y6482D03*
Y46482D03*
X176419Y6482D03*
Y26482D03*
X156419Y6482D03*
Y26482D03*
X176419Y46482D03*
X156419D03*
X136419Y66482D03*
Y86482D03*
X176419Y66482D03*
X156419D03*
X176419Y86482D03*
X156419D03*
X136419Y126482D03*
Y106482D03*
Y146482D03*
X176419Y126482D03*
Y106482D03*
X156419Y126482D03*
Y106482D03*
X176419Y146482D03*
X156419D03*
X136419Y186482D03*
Y166482D03*
X137398Y206936D03*
X176419Y186482D03*
Y166482D03*
X156419Y186482D03*
Y166482D03*
X177398Y206436D03*
X157398Y206936D03*
X137398Y226936D03*
Y246936D03*
Y266936D03*
X177398Y226936D03*
X157398D03*
X177398Y246936D03*
Y266936D03*
X157398Y246936D03*
Y266936D03*
X137398Y286936D03*
X177398D03*
X157398D03*
X135330Y337964D03*
Y377964D03*
Y357964D03*
X175330Y337964D03*
X155330D03*
X175330Y377964D03*
Y357964D03*
X155330Y377964D03*
Y357964D03*
X132000Y442500D03*
X135330Y417964D03*
X175500Y442000D03*
X175330Y417964D03*
X155000Y442000D03*
X155330Y417964D03*
X139898Y465436D03*
X159898D03*
X196419Y6482D03*
Y26482D03*
Y46482D03*
X236419Y6482D03*
Y26482D03*
X216419Y6482D03*
Y26482D03*
X236419Y46482D03*
X216419D03*
X196419Y66482D03*
Y86482D03*
X236419Y66482D03*
X216419D03*
X236419Y86482D03*
X216419D03*
X196419Y126482D03*
Y106482D03*
Y146482D03*
X236419Y126482D03*
Y106482D03*
X216419Y126482D03*
Y106482D03*
X236419Y146482D03*
X216419D03*
X196419Y186482D03*
Y166482D03*
X197398Y206436D03*
X236419Y186482D03*
Y166482D03*
X216419Y186482D03*
Y166482D03*
X217398Y206436D03*
X197398Y226936D03*
Y246936D03*
Y266936D03*
X217398Y226936D03*
Y246936D03*
Y266936D03*
X197398Y286936D03*
X217398D03*
X195330Y337964D03*
Y377964D03*
Y357964D03*
X235330Y337964D03*
X215330D03*
X235330Y377964D03*
Y357964D03*
X215330Y377964D03*
Y357964D03*
X196000Y442500D03*
X195330Y417964D03*
X235830Y442464D03*
X235330Y417964D03*
X215830Y442464D03*
X215330Y417964D03*
X179898Y465436D03*
X219898D03*
X199898D03*
X256419Y6482D03*
Y26482D03*
X276419Y6482D03*
Y26482D03*
X256419Y46482D03*
X276419D03*
X256419Y66482D03*
X273500Y66500D03*
X256419Y86482D03*
X274500Y86500D03*
X256419Y126482D03*
X276419D03*
X256419Y106482D03*
X274500Y106500D03*
X256419Y146482D03*
X276419D03*
X237398Y206436D03*
X256419Y186482D03*
X275500Y186500D03*
X251500Y166500D03*
X276419Y166482D03*
X257398Y206436D03*
X277398D03*
X237398Y226936D03*
Y246936D03*
Y266936D03*
X257398Y226936D03*
X277398D03*
X257398Y246936D03*
X277398D03*
X257398Y266936D03*
X277398D03*
X237398Y286936D03*
X257398D03*
X279398D03*
X255330Y337964D03*
X275330D03*
X255330Y377964D03*
X275330D03*
X255330Y357964D03*
X275330D03*
X255830Y442464D03*
X275830D03*
X255330Y417964D03*
X275330D03*
X239898Y465436D03*
X279898D03*
X259898D03*
X296419Y6482D03*
Y26482D03*
Y46482D03*
X316419Y6482D03*
Y26482D03*
X336419Y6482D03*
Y26482D03*
X316419Y46482D03*
X336419D03*
X302000Y67000D03*
X301000Y86500D03*
X316419Y66482D03*
X336419D03*
X316419Y86482D03*
X336419D03*
X296419Y126482D03*
X300000Y106500D03*
X296419Y146482D03*
X316419Y126482D03*
X336419D03*
X316419Y106482D03*
X336419D03*
X316419Y146482D03*
X336419D03*
X296419Y186482D03*
X295500Y169000D03*
X297398Y206436D03*
X317500Y186500D03*
X336419Y186482D03*
X317000Y166500D03*
X338500Y166000D03*
X317398Y206436D03*
X337398D03*
X297398Y226936D03*
Y246936D03*
Y266936D03*
X317398Y226936D03*
X337398D03*
X317398Y246936D03*
X337398D03*
X317398Y266936D03*
X337398D03*
X300398Y286936D03*
X317398D03*
X337398D03*
X295330Y337964D03*
Y377964D03*
Y357964D03*
X315330Y337964D03*
X335330D03*
X315330Y377964D03*
X335330D03*
X315330Y357964D03*
X335330D03*
X295830Y442464D03*
X295330Y417964D03*
X315830Y442464D03*
X335830D03*
X315330Y417964D03*
X335330D03*
X299898Y465436D03*
X339898D03*
X319898D03*
X356419Y6482D03*
Y26482D03*
Y46482D03*
X376419Y6482D03*
Y26482D03*
X396419Y6482D03*
Y26482D03*
X376419Y46482D03*
X396419D03*
X356419Y66482D03*
Y86482D03*
X376419Y66482D03*
X396419D03*
X376419Y86482D03*
X396419D03*
X356419Y126482D03*
Y106482D03*
Y146482D03*
X376419Y126482D03*
X396419D03*
X376419Y106482D03*
X396419D03*
X376419Y146482D03*
X396419D03*
X357500Y186500D03*
X354500Y166500D03*
X357398Y206436D03*
X376419Y186482D03*
X396419D03*
X380000Y166500D03*
X396419Y166482D03*
X377398Y206436D03*
X397398D03*
X357398Y226936D03*
Y246936D03*
Y266936D03*
X377398Y226936D03*
X397398D03*
X377398Y246936D03*
X397398D03*
X377398Y266936D03*
X397398D03*
X357398Y286936D03*
X377398D03*
X397398D03*
X355330Y337964D03*
Y377964D03*
Y357964D03*
X375330Y337964D03*
X395330D03*
X375330Y377964D03*
X395330D03*
X375330Y357964D03*
X395330D03*
X355830Y442464D03*
X355330Y417964D03*
X375830Y442464D03*
X395830D03*
X375330Y417964D03*
X395330D03*
X399898Y465436D03*
X379898D03*
X359898D03*
X416419Y6482D03*
Y26482D03*
X436419Y6482D03*
X416419Y46482D03*
X436419D03*
X456419D03*
X416419Y66482D03*
X436419D03*
X456419D03*
X416419Y86482D03*
X436419D03*
X456419D03*
X416419Y126482D03*
X436419D03*
X456419D03*
X416419Y106482D03*
X436419D03*
X456419D03*
X416419Y146482D03*
X436419D03*
X456419D03*
X416500Y166000D03*
X417519Y174482D03*
Y170282D03*
X425919D03*
X421719D03*
Y174482D03*
X431100Y174500D03*
Y170300D03*
X439500D03*
Y174500D03*
X435300Y170300D03*
Y174500D03*
X444100D03*
Y170300D03*
X452500D03*
Y174500D03*
X448300Y170300D03*
Y174500D03*
X457100Y175000D03*
Y170800D03*
X461300D03*
Y175000D03*
X418300Y197500D03*
Y201700D03*
X422500D03*
X426700D03*
X422500Y197500D03*
X426700D03*
X431300D03*
Y201700D03*
X435500D03*
X439700D03*
X435500Y197500D03*
X439700D03*
X444800D03*
Y201700D03*
X449000D03*
X453200D03*
X449000Y197500D03*
X453200D03*
X457800D03*
Y201700D03*
X462000D03*
Y197500D03*
X425919Y174482D03*
X436500Y166000D03*
X456500Y166500D03*
X417398Y206436D03*
X437398D03*
X457398D03*
X417398Y226936D03*
X437398D03*
X457398D03*
X417398Y246936D03*
X437398D03*
X457398D03*
X437398Y266936D03*
X457398D03*
X418398D03*
X437398Y286936D03*
X457398D03*
X418398D03*
X415330Y337964D03*
X435398Y338436D03*
X455398D03*
X415330Y377964D03*
Y357964D03*
X435398Y358436D03*
Y378436D03*
X455398Y358436D03*
Y378436D03*
X435830Y442464D03*
X455830D03*
X435330Y417964D03*
X455330D03*
X415830Y442464D03*
X415330Y417964D03*
X459898Y465436D03*
X439898D03*
X419898D03*
X516419Y6482D03*
X476419Y46482D03*
X496419D03*
X516419D03*
Y66482D03*
X476419D03*
X496419D03*
X516419Y86482D03*
X496419D03*
X476419D03*
Y126482D03*
X516419D03*
X496419D03*
X516419Y106482D03*
X496419D03*
X476419D03*
X485443Y160670D03*
X481243D03*
X493843D03*
X489643D03*
X476419Y146482D03*
X516419D03*
X496419D03*
X519221Y160912D03*
X510821D03*
X506621D03*
X515021D03*
X465500Y170800D03*
Y175000D03*
X466200Y201700D03*
Y197500D03*
X485443Y164870D03*
X481243D03*
X493843D03*
X489643D03*
X477284Y174586D03*
X473084D03*
Y170386D03*
X477284D03*
X498395Y174685D03*
Y170485D03*
X492911Y206602D03*
X488711D03*
X492911Y210802D03*
X488711D03*
X484511D03*
Y206602D03*
X480311Y210802D03*
Y206602D03*
X498052Y200389D03*
Y196189D03*
X477087Y201172D03*
X472887D03*
X477087Y196972D03*
X472887D03*
X519221Y165112D03*
X510821D03*
X506621D03*
X515021D03*
X502595Y174685D03*
Y170485D03*
X506135Y210557D03*
X510335D03*
X514535D03*
X518735D03*
X506135Y206357D03*
X510335D03*
X514535D03*
X518735D03*
X502252Y200389D03*
Y196189D03*
X497398Y226936D03*
X477398D03*
X520898Y228436D03*
X497398Y246936D03*
X477398D03*
Y266936D03*
X495398Y338436D03*
X475398D03*
X495398Y358436D03*
Y378436D03*
X475398Y358436D03*
Y378436D03*
X477000Y418000D03*
X499000Y418500D03*
X485510Y442620D03*
X505510D03*
X519898Y465436D03*
X499898D03*
X479898D03*
X533619Y6482D03*
Y26482D03*
Y46482D03*
X550819Y6482D03*
Y26482D03*
Y46482D03*
X568019Y6482D03*
Y26482D03*
Y46482D03*
X573623Y66967D03*
X536419Y66482D03*
X556419D03*
X536419Y86482D03*
X556419D03*
X576419Y106482D03*
Y126482D03*
X536419D03*
X556419D03*
X536419Y106482D03*
X556419D03*
X544476Y161322D03*
X531876D03*
X536076D03*
X540276D03*
X536419Y146482D03*
X556419D03*
X544477Y210389D03*
X544476Y165522D03*
X536076D03*
X531876D03*
X540276D03*
X552924Y175124D03*
X548724D03*
Y170924D03*
X552924D03*
X527711Y175174D03*
X523511D03*
Y170974D03*
X527711D03*
X531877Y210389D03*
X536077D03*
X540277D03*
X531877Y206189D03*
X536077D03*
X540277D03*
X544477D03*
X527761Y200632D03*
X523561D03*
X527761Y196432D03*
X523561D03*
X553171Y200877D03*
X548971D03*
X553171Y196677D03*
X548971D03*
X540898Y228436D03*
X560500Y268000D03*
X549500Y305500D03*
X559996Y282972D03*
X561500Y298000D03*
X534000Y282000D03*
X577500Y305000D03*
X634119Y26482D03*
X585219Y46482D03*
Y26482D03*
Y6482D03*
X602419Y26482D03*
Y6482D03*
X619619D03*
Y26482D03*
Y46482D03*
X634119D03*
Y6482D03*
X602419Y46482D03*
X628500Y104000D03*
X626500Y78500D03*
X611253Y65701D03*
X584543Y86671D03*
X611398Y86936D03*
X633753Y65701D03*
X633898Y86936D03*
X634000Y123500D03*
X607000D03*
X616000Y138000D03*
Y115500D03*
X594500Y117000D03*
X616000Y173500D03*
X615500Y199000D03*
X615898Y244436D03*
Y224436D03*
X615398Y266436D03*
X587500Y318500D03*
X600000Y298500D03*
X616498Y316236D03*
X615398Y284436D03*
X633398Y325436D03*
X630000Y345500D03*
Y387500D03*
X610898Y425436D03*
Y445436D03*
X632898Y404936D03*
Y444936D03*
Y424936D03*
X610898Y465436D03*
X632898Y464936D03*
G54D11*
X30157Y61023D03*
Y415354D03*
%LPC*%
G75*
G54D22*
G01X-4246Y-109426D02*
Y-189426D01*
G01D02*
X1290354D01*
G01X-4246Y-144926D02*
X1290354D01*
G01X-8246Y-93426D02*
G02I-12000J0D01*
G01X-13396D02*
G02I-6850J0D01*
G01X-20246Y-109426D02*
Y-77426D01*
G01X-4246Y-93426D02*
X-36246D01*
G01X-4246Y-109426D02*
X1290354D01*
G01X502854D02*
Y-189426D01*
G01X640354Y-109426D02*
Y-189426D01*
G01X755354Y-109426D02*
Y-189426D01*
G01X922854Y-109426D02*
Y-189426D01*
G01X1092854Y-109426D02*
Y-189426D01*
G01X1290354Y-109426D02*
Y-189426D01*
G01X1318354Y-93426D02*
G02I-12000J0D01*
G01X1313204D02*
G02I-6850J0D01*
G01X1306354Y-109426D02*
Y-77426D01*
G01X1322354Y-93426D02*
X1290354D01*
G54D23*
G01X16751Y-179426D02*
Y-161926D01*
G01X25047D02*
X16751Y-172718D01*
G01X26357Y-179426D02*
X20462Y-167760D01*
G01X34032Y-179426D02*
Y-161926D01*
X44076Y-179426D01*
Y-161926D01*
G01X56554Y-179426D02*
X54807Y-179134D01*
X53279Y-177968D01*
X51969Y-176218D01*
X51095Y-174176D01*
X50659Y-171843D01*
Y-169509D01*
X51095Y-167176D01*
X51969Y-165134D01*
X53279Y-163385D01*
X54807Y-162218D01*
X56554Y-161926D01*
X58300Y-162218D01*
X59829Y-163385D01*
X61139Y-165134D01*
X62013Y-167176D01*
X62449Y-169509D01*
Y-171843D01*
X62013Y-174176D01*
X61139Y-176218D01*
X59829Y-177968D01*
X58300Y-179134D01*
X56554Y-179426D01*
G01X69469D02*
X78639Y-161926D01*
G01X69469D02*
X78639Y-179426D01*
G01X104687D02*
Y-161926D01*
X109927D01*
X111674Y-162801D01*
X112984Y-164843D01*
X113421Y-167176D01*
X112984Y-169509D01*
X111892Y-171259D01*
X109927Y-172135D01*
X104687D01*
G01X126554Y-179426D02*
X124807Y-179134D01*
X123279Y-177968D01*
X121969Y-176218D01*
X121095Y-174176D01*
X120659Y-171843D01*
Y-169509D01*
X121095Y-167176D01*
X121969Y-165134D01*
X123279Y-163385D01*
X124807Y-162218D01*
X126554Y-161926D01*
X128300Y-162218D01*
X129829Y-163385D01*
X131139Y-165134D01*
X132013Y-167176D01*
X132449Y-169509D01*
Y-171843D01*
X132013Y-174176D01*
X131139Y-176218D01*
X129829Y-177968D01*
X128300Y-179134D01*
X126554Y-179426D01*
G01X137504Y-161926D02*
X140560Y-179426D01*
X144054Y-161926D01*
X147547Y-179426D01*
X150604Y-161926D01*
G01X165921Y-179426D02*
X157187D01*
Y-161926D01*
X165921D01*
G01X162427Y-170384D02*
X157187D01*
G01X174687Y-179426D02*
Y-161926D01*
X180146D01*
X181892Y-162801D01*
X182984Y-163968D01*
X183421Y-166301D01*
X182984Y-168635D01*
X181674Y-170093D01*
X180146Y-170968D01*
X174687D01*
G01X180146D02*
X183421Y-179426D01*
G01X214054Y-161926D02*
Y-179426D01*
G01X209032Y-161926D02*
X219076D01*
G01X227187Y-179426D02*
Y-161926D01*
X232646D01*
X234392Y-162801D01*
X235484Y-163968D01*
X235921Y-166301D01*
X235484Y-168635D01*
X234174Y-170093D01*
X232646Y-170968D01*
X227187D01*
G01X232646D02*
X235921Y-179426D01*
G01X243595D02*
X249054Y-161926D01*
X254513Y-179426D01*
G01X252547Y-173301D02*
X245560D01*
G01X261532Y-179426D02*
Y-161926D01*
X271576Y-179426D01*
Y-161926D01*
G01X279469Y-177093D02*
X281216Y-178551D01*
X283181Y-179426D01*
X284927D01*
X286674Y-178551D01*
X287984Y-177093D01*
X288639Y-175051D01*
X288202Y-173010D01*
X287111Y-171259D01*
X285146Y-170093D01*
X282526Y-169509D01*
X280997Y-168343D01*
X280342Y-166301D01*
X280779Y-164259D01*
X281871Y-162801D01*
X283399Y-161926D01*
X284927D01*
X286456Y-162509D01*
X287766Y-163968D01*
G01X298934Y-161926D02*
X304174D01*
G01X301554D02*
Y-179426D01*
G01X298934D02*
X304174D01*
G01X319054Y-161926D02*
Y-179426D01*
G01X314032Y-161926D02*
X324076D01*
G01X333934D02*
X339174D01*
G01X336554D02*
Y-179426D01*
G01X333934D02*
X339174D01*
G01X354054D02*
X352307Y-179134D01*
X350779Y-177968D01*
X349469Y-176218D01*
X348595Y-174176D01*
X348159Y-171843D01*
Y-169509D01*
X348595Y-167176D01*
X349469Y-165134D01*
X350779Y-163385D01*
X352307Y-162218D01*
X354054Y-161926D01*
X355800Y-162218D01*
X357329Y-163385D01*
X358639Y-165134D01*
X359513Y-167176D01*
X359949Y-169509D01*
Y-171843D01*
X359513Y-174176D01*
X358639Y-176218D01*
X357329Y-177968D01*
X355800Y-179134D01*
X354054Y-179426D01*
G01X366532D02*
Y-161926D01*
X376576Y-179426D01*
Y-161926D01*
G01X408300Y-170093D02*
X409174Y-169218D01*
X409829Y-167760D01*
X410266Y-165717D01*
X409829Y-163968D01*
X408956Y-162801D01*
X407427Y-161926D01*
X401532D01*
Y-179426D01*
X408737D01*
X410266Y-178260D01*
X411139Y-176509D01*
X411576Y-174468D01*
X411139Y-172426D01*
X409829Y-170676D01*
X408300Y-170093D01*
X401532D01*
G01X424054Y-179426D02*
X422307Y-179134D01*
X420779Y-177968D01*
X419469Y-176218D01*
X418595Y-174176D01*
X418159Y-171843D01*
Y-169509D01*
X418595Y-167176D01*
X419469Y-165134D01*
X420779Y-163385D01*
X422307Y-162218D01*
X424054Y-161926D01*
X425800Y-162218D01*
X427329Y-163385D01*
X428639Y-165134D01*
X429513Y-167176D01*
X429949Y-169509D01*
Y-171843D01*
X429513Y-174176D01*
X428639Y-176218D01*
X427329Y-177968D01*
X425800Y-179134D01*
X424054Y-179426D01*
G01X436095D02*
X441554Y-161926D01*
X447013Y-179426D01*
G01X445047Y-173301D02*
X438060D01*
G01X454687Y-179426D02*
Y-161926D01*
X460146D01*
X461892Y-162801D01*
X462984Y-163968D01*
X463421Y-166301D01*
X462984Y-168635D01*
X461674Y-170093D01*
X460146Y-170968D01*
X454687D01*
G01X460146D02*
X463421Y-179426D01*
G01X471751D02*
Y-161926D01*
X476117D01*
X477864Y-162801D01*
X479174Y-163968D01*
X480266Y-165717D01*
X481139Y-167760D01*
X481357Y-170676D01*
X481139Y-173593D01*
X480266Y-175635D01*
X479174Y-177385D01*
X477864Y-178551D01*
X476117Y-179426D01*
X471751D01*
G01X208377Y-134426D02*
Y-116926D01*
X214054Y-131509D01*
X219731Y-116926D01*
Y-134426D01*
G01X231554D02*
X230244Y-134134D01*
X228934Y-132968D01*
X228060Y-130926D01*
X227624Y-128593D01*
X228060Y-126259D01*
X228934Y-124218D01*
X230244Y-123051D01*
X231554Y-122760D01*
X232864Y-123051D01*
X234174Y-124218D01*
X235047Y-126259D01*
X235266Y-128593D01*
X235047Y-130926D01*
X234174Y-132968D01*
X232864Y-134134D01*
X231554Y-134426D01*
G01X252984Y-116926D02*
Y-134426D01*
G01Y-131802D02*
X252111Y-133260D01*
X250800Y-134134D01*
X249272Y-134426D01*
X247526Y-133843D01*
X246216Y-132385D01*
X245342Y-130635D01*
X245124Y-128593D01*
X245342Y-126551D01*
X246216Y-124801D01*
X247526Y-123343D01*
X249272Y-122760D01*
X250800Y-123051D01*
X251892Y-123635D01*
X252984Y-124801D01*
G01X263279Y-126551D02*
X270266D01*
X269611Y-124509D01*
X268519Y-123343D01*
X266991Y-122760D01*
X265462Y-123051D01*
X264152Y-123926D01*
X263279Y-125968D01*
X262842Y-127718D01*
Y-129468D01*
X263279Y-131218D01*
X264371Y-132968D01*
X265681Y-134134D01*
X267209Y-134426D01*
X268737Y-133843D01*
X270266Y-132093D01*
G01X284054Y-134426D02*
Y-116926D01*
G01X536554Y-179426D02*
Y-161926D01*
X533934Y-165426D01*
G01Y-179426D02*
X539174D01*
G01X549906Y-164843D02*
X551216Y-163093D01*
X552744Y-162218D01*
X554491Y-161926D01*
X556674Y-162509D01*
X558202Y-163968D01*
X558639Y-165717D01*
X558421Y-167468D01*
X557547Y-168926D01*
X553181Y-171843D01*
X551216Y-173884D01*
X549906Y-176802D01*
X549469Y-179426D01*
X558639D01*
G01X566751Y-176802D02*
X568060Y-178260D01*
X569589Y-179134D01*
X571554Y-179426D01*
X573519Y-178843D01*
X575047Y-177676D01*
X576139Y-175635D01*
X576357Y-173301D01*
X575921Y-170968D01*
X574829Y-169509D01*
X573300Y-168343D01*
X571772Y-168051D01*
X570244Y-168343D01*
X568279Y-169509D01*
X568934Y-161926D01*
X574829D01*
G01X584906Y-164843D02*
X586216Y-163093D01*
X587744Y-162218D01*
X589491Y-161926D01*
X591674Y-162509D01*
X593202Y-163968D01*
X593639Y-165717D01*
X593421Y-167468D01*
X592547Y-168926D01*
X588181Y-171843D01*
X586216Y-173884D01*
X584906Y-176802D01*
X584469Y-179426D01*
X593639D01*
G01X601751Y-175926D02*
X603060Y-177968D01*
X604807Y-179134D01*
X606772Y-179426D01*
X608519Y-179134D01*
X610266Y-177676D01*
X611357Y-175926D01*
X611576Y-174176D01*
X611139Y-172135D01*
X609611Y-170676D01*
X608082Y-170093D01*
X606117D01*
G01X608082D02*
X609392Y-169218D01*
X610484Y-167760D01*
X610921Y-166010D01*
X610484Y-164259D01*
X609392Y-162801D01*
X607427Y-161926D01*
X605462Y-162218D01*
X603497Y-163385D01*
G01X523437Y-134426D02*
Y-116926D01*
X528677D01*
X530424Y-117801D01*
X531734Y-119843D01*
X532171Y-122176D01*
X531734Y-124509D01*
X530642Y-126259D01*
X528677Y-127135D01*
X523437D01*
G01X550107Y-118385D02*
X548797Y-117509D01*
X547269Y-116926D01*
X545522D01*
X543557Y-117801D01*
X542029Y-119259D01*
X540937Y-121010D01*
X540064Y-123926D01*
X539845Y-126551D01*
X540282Y-129176D01*
X540937Y-130926D01*
X542247Y-132676D01*
X543776Y-133843D01*
X545304Y-134426D01*
X546832D01*
X548361Y-133843D01*
X549671Y-132968D01*
X550763Y-131802D01*
G01X564550Y-125093D02*
X565424Y-124218D01*
X566079Y-122760D01*
X566516Y-120717D01*
X566079Y-118968D01*
X565206Y-117801D01*
X563677Y-116926D01*
X557782D01*
Y-134426D01*
X564987D01*
X566516Y-133260D01*
X567389Y-131509D01*
X567826Y-129468D01*
X567389Y-127426D01*
X566079Y-125676D01*
X564550Y-125093D01*
X557782D01*
G01X573754Y-140259D02*
X586854D01*
G01X592782Y-134426D02*
Y-116926D01*
X602826Y-134426D01*
Y-116926D01*
G01X615304Y-134426D02*
X613557Y-134134D01*
X612029Y-132968D01*
X610719Y-131218D01*
X609845Y-129176D01*
X609409Y-126843D01*
Y-124509D01*
X609845Y-122176D01*
X610719Y-120134D01*
X612029Y-118385D01*
X613557Y-117218D01*
X615304Y-116926D01*
X617050Y-117218D01*
X618579Y-118385D01*
X619889Y-120134D01*
X620763Y-122176D01*
X621199Y-124509D01*
Y-126843D01*
X620763Y-129176D01*
X619889Y-131218D01*
X618579Y-132968D01*
X617050Y-134134D01*
X615304Y-134426D01*
G01X697854Y-179426D02*
Y-161926D01*
X695234Y-165426D01*
G01Y-179426D02*
X700474D01*
G01X666145Y-116926D02*
X671604Y-134426D01*
X677063Y-116926D01*
G01X693471Y-134426D02*
X684737D01*
Y-116926D01*
X693471D01*
G01X689977Y-125384D02*
X684737D01*
G01X702237Y-134426D02*
Y-116926D01*
X707696D01*
X709442Y-117801D01*
X710534Y-118968D01*
X710971Y-121301D01*
X710534Y-123635D01*
X709224Y-125093D01*
X707696Y-125968D01*
X702237D01*
G01X707696D02*
X710971Y-134426D01*
G01X724104Y-135009D02*
X723667Y-134718D01*
Y-134134D01*
X724104Y-133843D01*
X724541Y-134134D01*
Y-134718D01*
X724104Y-135009D01*
G01X878421Y-161926D02*
Y-179426D01*
X869687D01*
G01X861357Y-175926D02*
X860048Y-177968D01*
X858301Y-179134D01*
X856336Y-179426D01*
X854589Y-179134D01*
X852842Y-177676D01*
X851751Y-175926D01*
X851532Y-174176D01*
X851969Y-172135D01*
X853497Y-170676D01*
X855026Y-170093D01*
X856991D01*
G01X855026D02*
X853716Y-169218D01*
X852624Y-167760D01*
X852187Y-166010D01*
X852624Y-164259D01*
X853716Y-162801D01*
X855681Y-161926D01*
X857646Y-162218D01*
X859611Y-163385D01*
G01X844513Y-161926D02*
X839054Y-179426D01*
X833595Y-161926D01*
G01X816751Y-163385D02*
X818061Y-162509D01*
X819589Y-161926D01*
X821336D01*
X823301Y-162801D01*
X824829Y-164259D01*
X825921Y-166010D01*
X826794Y-168926D01*
X827013Y-171551D01*
X826576Y-174176D01*
X825921Y-175926D01*
X824611Y-177676D01*
X823082Y-178843D01*
X821554Y-179426D01*
X820026D01*
X818497Y-178843D01*
X817187Y-177968D01*
X816095Y-176802D01*
G01X799251Y-163385D02*
X800561Y-162509D01*
X802089Y-161926D01*
X803836D01*
X805801Y-162801D01*
X807329Y-164259D01*
X808421Y-166010D01*
X809294Y-168926D01*
X809513Y-171551D01*
X809076Y-174176D01*
X808421Y-175926D01*
X807111Y-177676D01*
X805582Y-178843D01*
X804054Y-179426D01*
X802526D01*
X800997Y-178843D01*
X799687Y-177968D01*
X798595Y-176802D01*
G01X790937Y-116926D02*
Y-134426D01*
X799671D01*
G01X816734D02*
Y-122760D01*
G01Y-124801D02*
X815861Y-123635D01*
X814550Y-123051D01*
X813022Y-122760D01*
X811494Y-123343D01*
X810184Y-124509D01*
X809310Y-126259D01*
X808874Y-128593D01*
X809310Y-130926D01*
X810184Y-132676D01*
X811494Y-133843D01*
X813022Y-134426D01*
X814550Y-134134D01*
X815861Y-133260D01*
X816734Y-132093D01*
G01X825719Y-139676D02*
X827029Y-140259D01*
X828776Y-139676D01*
X829867Y-138510D01*
X830741Y-137051D01*
X832050Y-132385D01*
X834889Y-122760D01*
G01X827902D02*
X832050Y-132385D01*
G01X844529Y-126551D02*
X851516D01*
X850861Y-124509D01*
X849769Y-123343D01*
X848241Y-122760D01*
X846712Y-123051D01*
X845402Y-123926D01*
X844529Y-125968D01*
X844092Y-127718D01*
Y-129468D01*
X844529Y-131218D01*
X845621Y-132968D01*
X846931Y-134134D01*
X848459Y-134426D01*
X849987Y-133843D01*
X851516Y-132093D01*
G01X862247Y-134426D02*
Y-122760D01*
G01Y-125093D02*
X863339Y-123926D01*
X864431Y-123051D01*
X865959Y-122760D01*
X867050Y-123051D01*
X868361Y-123926D01*
G01X879529Y-132385D02*
X880621Y-133551D01*
X882149Y-134426D01*
X883459D01*
X884769Y-133843D01*
X885642Y-132968D01*
X886079Y-131802D01*
X885861Y-130051D01*
X884987Y-129176D01*
X881057Y-127426D01*
X880184Y-125384D01*
X880621Y-123926D01*
X881494Y-123051D01*
X882804Y-122760D01*
X884114Y-123051D01*
X885424Y-123926D01*
G01X924737Y-175926D02*
X925829Y-177676D01*
X927139Y-178843D01*
X928667Y-179426D01*
X930414Y-178843D01*
X931724Y-177676D01*
X933034Y-175926D01*
X933471Y-173593D01*
Y-161926D01*
G01X946604Y-179426D02*
X944857Y-179134D01*
X943329Y-177968D01*
X942019Y-176218D01*
X941145Y-174176D01*
X940709Y-171843D01*
Y-169509D01*
X941145Y-167176D01*
X942019Y-165134D01*
X943329Y-163385D01*
X944857Y-162218D01*
X946604Y-161926D01*
X948350Y-162218D01*
X949879Y-163385D01*
X951189Y-165134D01*
X952063Y-167176D01*
X952499Y-169509D01*
Y-171843D01*
X952063Y-174176D01*
X951189Y-176218D01*
X949879Y-177968D01*
X948350Y-179134D01*
X946604Y-179426D01*
G01X959519Y-177093D02*
X961266Y-178551D01*
X963231Y-179426D01*
X964977D01*
X966724Y-178551D01*
X968034Y-177093D01*
X968689Y-175051D01*
X968252Y-173010D01*
X967161Y-171259D01*
X965196Y-170093D01*
X962576Y-169509D01*
X961047Y-168343D01*
X960392Y-166301D01*
X960829Y-164259D01*
X961921Y-162801D01*
X963449Y-161926D01*
X964977D01*
X966506Y-162509D01*
X967816Y-163968D01*
G01X985971Y-179426D02*
X977237D01*
Y-161926D01*
X985971D01*
G01X982477Y-170384D02*
X977237D01*
G01X994737Y-179426D02*
Y-161926D01*
X999977D01*
X1001724Y-162801D01*
X1003034Y-164843D01*
X1003471Y-167176D01*
X1003034Y-169509D01*
X1001942Y-171259D01*
X999977Y-172135D01*
X994737D01*
G01X1012019Y-179426D02*
Y-161926D01*
G01X1021189D02*
Y-179426D01*
G01Y-170676D02*
X1012019D01*
G01X1047237Y-161926D02*
Y-179426D01*
X1055971D01*
G01X1063645D02*
X1069104Y-161926D01*
X1074563Y-179426D01*
G01X1072597Y-173301D02*
X1065610D01*
G01X1081801Y-161926D02*
Y-174468D01*
X1082674Y-177093D01*
X1084421Y-178843D01*
X1086604Y-179426D01*
X1088787Y-178843D01*
X1090534Y-177093D01*
X1091407Y-174468D01*
Y-161926D01*
G01X941801Y-134426D02*
Y-116926D01*
X946167D01*
X947914Y-117801D01*
X949224Y-118968D01*
X950316Y-120717D01*
X951189Y-122760D01*
X951407Y-125676D01*
X951189Y-128593D01*
X950316Y-130635D01*
X949224Y-132385D01*
X947914Y-133551D01*
X946167Y-134426D01*
X941801D01*
G01X960829Y-126551D02*
X967816D01*
X967161Y-124509D01*
X966069Y-123343D01*
X964541Y-122760D01*
X963012Y-123051D01*
X961702Y-123926D01*
X960829Y-125968D01*
X960392Y-127718D01*
Y-129468D01*
X960829Y-131218D01*
X961921Y-132968D01*
X963231Y-134134D01*
X964759Y-134426D01*
X966287Y-133843D01*
X967816Y-132093D01*
G01X978329Y-132385D02*
X979421Y-133551D01*
X980949Y-134426D01*
X982259D01*
X983569Y-133843D01*
X984442Y-132968D01*
X984879Y-131802D01*
X984661Y-130051D01*
X983787Y-129176D01*
X979857Y-127426D01*
X978984Y-125384D01*
X979421Y-123926D01*
X980294Y-123051D01*
X981604Y-122760D01*
X982914Y-123051D01*
X984224Y-123926D01*
G01X999104Y-122760D02*
Y-134426D01*
G01Y-118093D02*
X998667Y-117801D01*
Y-117218D01*
X999104Y-116926D01*
X999541Y-117218D01*
Y-117801D01*
X999104Y-118093D01*
G01X1013547Y-138801D02*
X1015076Y-139968D01*
X1016822Y-140259D01*
X1018350Y-139968D01*
X1019661Y-138510D01*
X1020534Y-136468D01*
Y-122760D01*
G01Y-125093D02*
X1019661Y-123926D01*
X1018350Y-123051D01*
X1016822Y-122760D01*
X1015076Y-123343D01*
X1013984Y-124509D01*
X1013110Y-126551D01*
X1012674Y-128593D01*
X1012892Y-130343D01*
X1013766Y-132385D01*
X1015076Y-133843D01*
X1016822Y-134426D01*
X1018132Y-134134D01*
X1019661Y-132968D01*
X1020534Y-131802D01*
G01X1030392Y-134426D02*
Y-122760D01*
G01Y-125676D02*
X1031266Y-124218D01*
X1032576Y-123051D01*
X1034322Y-122760D01*
X1035850Y-123051D01*
X1037161Y-124218D01*
X1037816Y-126259D01*
Y-134426D01*
G01X1048329Y-126551D02*
X1055316D01*
X1054661Y-124509D01*
X1053569Y-123343D01*
X1052041Y-122760D01*
X1050512Y-123051D01*
X1049202Y-123926D01*
X1048329Y-125968D01*
X1047892Y-127718D01*
Y-129468D01*
X1048329Y-131218D01*
X1049421Y-132968D01*
X1050731Y-134134D01*
X1052259Y-134426D01*
X1053787Y-133843D01*
X1055316Y-132093D01*
G01X1066047Y-134426D02*
Y-122760D01*
G01Y-125093D02*
X1067139Y-123926D01*
X1068231Y-123051D01*
X1069759Y-122760D01*
X1070850Y-123051D01*
X1072161Y-123926D01*
G01X1112804Y-179426D02*
Y-161926D01*
X1110184Y-165426D01*
G01Y-179426D02*
X1115424D01*
G01X1130304Y-161926D02*
X1128557Y-162509D01*
X1127247Y-163968D01*
X1126374Y-165717D01*
X1125719Y-168051D01*
X1125501Y-170676D01*
X1125719Y-173301D01*
X1126374Y-175635D01*
X1127247Y-177385D01*
X1128557Y-178843D01*
X1130304Y-179426D01*
X1132050Y-178843D01*
X1133361Y-177385D01*
X1134234Y-175635D01*
X1134889Y-173301D01*
X1135107Y-170676D01*
X1134889Y-168051D01*
X1134234Y-165717D01*
X1133361Y-163968D01*
X1132050Y-162509D01*
X1130304Y-161926D01*
G01X1143874Y-180009D02*
X1151734Y-161926D01*
G01X1165304Y-179426D02*
Y-161926D01*
X1162684Y-165426D01*
G01Y-179426D02*
X1167924D01*
G01X1179092Y-177385D02*
X1180621Y-178843D01*
X1182367Y-179426D01*
X1184114Y-178843D01*
X1185642Y-177093D01*
X1186734Y-174468D01*
X1187171Y-171843D01*
Y-168635D01*
X1186734Y-166010D01*
X1185642Y-163676D01*
X1184332Y-162509D01*
X1182804Y-161926D01*
X1181057Y-162509D01*
X1179747Y-163676D01*
X1178874Y-165426D01*
X1178437Y-167760D01*
X1178874Y-169801D01*
X1179966Y-171843D01*
X1181276Y-173010D01*
X1182804Y-173301D01*
X1184550Y-172718D01*
X1185861Y-171259D01*
X1187171Y-168635D01*
G01X1196374Y-180009D02*
X1204234Y-161926D01*
G01X1213656Y-164843D02*
X1214966Y-163093D01*
X1216494Y-162218D01*
X1218241Y-161926D01*
X1220424Y-162509D01*
X1221952Y-163968D01*
X1222389Y-165717D01*
X1222171Y-167468D01*
X1221297Y-168926D01*
X1216931Y-171843D01*
X1214966Y-173884D01*
X1213656Y-176802D01*
X1213219Y-179426D01*
X1222389D01*
G01X1235304Y-161926D02*
X1233557Y-162509D01*
X1232247Y-163968D01*
X1231374Y-165717D01*
X1230719Y-168051D01*
X1230501Y-170676D01*
X1230719Y-173301D01*
X1231374Y-175635D01*
X1232247Y-177385D01*
X1233557Y-178843D01*
X1235304Y-179426D01*
X1237050Y-178843D01*
X1238361Y-177385D01*
X1239234Y-175635D01*
X1239889Y-173301D01*
X1240107Y-170676D01*
X1239889Y-168051D01*
X1239234Y-165717D01*
X1238361Y-163968D01*
X1237050Y-162509D01*
X1235304Y-161926D01*
G01X1252804Y-179426D02*
Y-161926D01*
X1250184Y-165426D01*
G01Y-179426D02*
X1255424D01*
G01X1266156Y-164843D02*
X1267466Y-163093D01*
X1268994Y-162218D01*
X1270741Y-161926D01*
X1272924Y-162509D01*
X1274452Y-163968D01*
X1274889Y-165717D01*
X1274671Y-167468D01*
X1273797Y-168926D01*
X1269431Y-171843D01*
X1267466Y-173884D01*
X1266156Y-176802D01*
X1265719Y-179426D01*
X1274889D01*
G01X1160501Y-134426D02*
Y-116926D01*
X1164867D01*
X1166614Y-117801D01*
X1167924Y-118968D01*
X1169016Y-120717D01*
X1169889Y-122760D01*
X1170107Y-125676D01*
X1169889Y-128593D01*
X1169016Y-130635D01*
X1167924Y-132385D01*
X1166614Y-133551D01*
X1164867Y-134426D01*
X1160501D01*
G01X1186734D02*
Y-122760D01*
G01Y-124801D02*
X1185861Y-123635D01*
X1184550Y-123051D01*
X1183022Y-122760D01*
X1181494Y-123343D01*
X1180184Y-124509D01*
X1179310Y-126259D01*
X1178874Y-128593D01*
X1179310Y-130926D01*
X1180184Y-132676D01*
X1181494Y-133843D01*
X1183022Y-134426D01*
X1184550Y-134134D01*
X1185861Y-133260D01*
X1186734Y-132093D01*
G01X1200304Y-116926D02*
Y-134426D01*
G01X1197247Y-122760D02*
X1203361D01*
G01X1214529Y-126551D02*
X1221516D01*
X1220861Y-124509D01*
X1219769Y-123343D01*
X1218241Y-122760D01*
X1216712Y-123051D01*
X1215402Y-123926D01*
X1214529Y-125968D01*
X1214092Y-127718D01*
Y-129468D01*
X1214529Y-131218D01*
X1215621Y-132968D01*
X1216931Y-134134D01*
X1218459Y-134426D01*
X1219987Y-133843D01*
X1221516Y-132093D01*
M02*
